# BASEBOARD_FAB2 (Tioga Pass) — schematic netlist excerpt (pin names and nets, part order shuffled) for the footprints in the layout excerpt that follows; sources: Cadence DE-HDL packaged netlist, KiCad conversion of Wiwynn_Tioga_Pass_MB.brd

R3P58  RES  0.0 5% CHIP  pkg 0402  page 92 : A = H_CPU1_CATERR_G_N ; B = H_CPU_CATERR_G_N
C1M35  CAP_A  0.01UF 25V 10% X7R  pkg 0402V  page 113 : A = P3V3_STBY ; B = GND
C2U8  CAP  0.22UF 16V 10% X7R  pkg 0402  page 107 : A = P3E_CPU0_PE1_PCH_RXN<2> ; B = P3E_CPU0_PE1_SS_RXN<2>

(kicad_pcb
	(version 20260206)
	(generator "pcbnew")
	(generator_version "10.0")
	(general
		(thickness 1.6)
		(legacy_teardrops no)
	)
	(paper "A4")
	(title_block
		(title "Wiwynn_Tioga_Pass_MB.brd")
		(comment 1 "Tioga Pass / footprints 2867-2869 of 4770")
	)
	(layers
		(0 "F.Cu" signal "TOP")
		(4 "In1.Cu" signal "L2GND")
		(6 "In2.Cu" signal "L3")
		(8 "In3.Cu" signal "L4GND")
		(10 "In4.Cu" signal "L5")
		(12 "In5.Cu" signal "L6GND")
		(14 "In6.Cu" signal "L7VCC")
		(16 "In7.Cu" signal "L8VCC")
		(18 "In8.Cu" signal "L9GND")
		(20 "In9.Cu" signal "L10")
		(22 "In10.Cu" signal "L11GND")
		(24 "In11.Cu" signal "L12")
		(26 "In12.Cu" signal "L13GND")
		(2 "B.Cu" signal "BOTTOM")
		(9 "F.Adhes" user "F.Adhesive")
		(11 "B.Adhes" user "B.Adhesive")
		(13 "F.Paste" user "Package Geometry/Pastemask Top")
		(15 "B.Paste" user "Package Geometry/Pastemask Bottom")
		(5 "F.SilkS" user "Ref Des/Silkscreen Top")
		(7 "B.SilkS" user "Ref Des/Silkscreen Bottom")
		(1 "F.Mask" user "Board Geometry/Soldermask Top")
		(3 "B.Mask" user "Board Geometry/Soldermask Bottom")
		(17 "Dwgs.User" user "User.Drawings")
		(19 "Cmts.User" user "User.Comments")
		(21 "Eco1.User" user "User.Eco1")
		(23 "Eco2.User" user "User.Eco2")
		(25 "Edge.Cuts" user "Board Geometry/Outline")
		(27 "Margin" user)
		(31 "F.CrtYd" user "Package Geometry/Place Bound Top")
		(29 "B.CrtYd" user "Package Geometry/Place Bound Bottom")
		(35 "F.Fab" user "Ref Des/Assembly Top")
		(33 "B.Fab" user "Ref Des/Assembly Bottom")
	)
	(footprint ""
		(layer "B.Cu")
		(at 448.2846 -129.3622 180)
		(property "Reference" "C1M35"
			(at 0 0 0)
			(layer "B.SilkS")
			(hide yes)
			(effects
				(font
					(size 1.27 1.27)
				)
				(justify mirror)
			)
		)
		(property "Value" ""
			(at 0 0 0)
			(layer "B.Fab")
			(effects
				(font
					(size 1.27 1.27)
				)
				(justify mirror)
			)
		)
		(duplicate_pad_numbers_are_jumpers no)
		(fp_poly
			(pts
				(xy -0.3048 -0.1016) (xy -0.3048 0.9906) (xy 0.3048 0.9906) (xy 0.3048 -0.1016)
			)
			(stroke
				(width 0)
				(type default)
			)
			(fill no)
			(layer "B.CrtYd")
		)
		(fp_line
			(start 0.3048 0.9906)
			(end -0.3048 0.9906)
			(stroke
				(width 0.1)
				(type default)
			)
			(layer "B.Fab")
		)
		(fp_line
			(start 0.3048 -0.1016)
			(end 0.3048 0.9906)
			(stroke
				(width 0.1)
				(type default)
			)
			(layer "B.Fab")
		)
		(fp_line
			(start -0.3048 0.9906)
			(end -0.3048 -0.1016)
			(stroke
				(width 0.1)
				(type default)
			)
			(layer "B.Fab")
		)
		(fp_line
			(start -0.3048 -0.1016)
			(end 0.3048 -0.1016)
			(stroke
				(width 0.1)
				(type default)
			)
			(layer "B.Fab")
		)
		(pad "1" smd rect
			(at 0 0)
			(size 0.508 0.508)
			(layers "B.Cu" "B.Mask" "B.Paste")
			(net "P3V3_STBY")
		)
		(pad "2" smd rect
			(at 0 0.889)
			(size 0.508 0.508)
			(layers "B.Cu" "B.Mask" "B.Paste")
			(net "GND")
		)
		(zone
			(layer "B.Cu")
			(hatch none 0.5)
			(connect_pads
				(clearance 0)
			)
			(min_thickness 0.25)
			(keepout
				(tracks not_allowed)
				(vias allowed)
				(pads allowed)
				(copperpour not_allowed)
				(footprints allowed)
			)
			(placement
				(enabled no)
				(sheetname "")
			)
			(fill
				(thermal_gap 0.5)
				(thermal_bridge_width 0.5)
				(island_removal_mode 0)
			)
			(polygon
				(pts
					(xy 448.0306 -129.9972) (xy 448.5386 -129.9972) (xy 448.5386 -129.6162) (xy 448.0306 -129.6162)
				)
			)
		)
		(zone
			(layer "B.Cu")
			(hatch none 0.5)
			(connect_pads
				(clearance 0)
			)
			(min_thickness 0.25)
			(keepout
				(tracks allowed)
				(vias not_allowed)
				(pads allowed)
				(copperpour not_allowed)
				(footprints allowed)
			)
			(placement
				(enabled no)
				(sheetname "")
			)
			(fill
				(thermal_gap 0.5)
				(thermal_bridge_width 0.5)
				(island_removal_mode 0)
			)
			(polygon
				(pts
					(xy 448.0306 -129.6162) (xy 448.5386 -129.6162) (xy 448.5386 -129.9972) (xy 448.0306 -129.9972)
				)
			)
		)
	)
	(footprint ""
		(layer "B.Cu")
		(at 373.6975 -57.658 -90)
		(property "Reference" "R3P58"
			(at 0 0 90)
			(layer "B.SilkS")
			(hide yes)
			(effects
				(font
					(size 1.27 1.27)
				)
				(justify mirror)
			)
		)
		(property "Value" ""
			(at 0 0 90)
			(layer "B.Fab")
			(effects
				(font
					(size 1.27 1.27)
				)
				(justify mirror)
			)
		)
		(duplicate_pad_numbers_are_jumpers no)
		(fp_poly
			(pts
				(xy 0.2794 -0.1016) (xy -0.2794 -0.1016) (xy -0.2794 0.9906) (xy 0.2794 0.9906)
			)
			(stroke
				(width 0)
				(type default)
			)
			(fill no)
			(layer "B.CrtYd")
		)
		(fp_line
			(start -0.2794 0.9906)
			(end -0.2794 -0.1016)
			(stroke
				(width 0.1)
				(type default)
			)
			(layer "B.Fab")
		)
		(fp_line
			(start 0.2794 0.9906)
			(end -0.2794 0.9906)
			(stroke
				(width 0.1)
				(type default)
			)
			(layer "B.Fab")
		)
		(fp_line
			(start -0.2794 -0.1016)
			(end 0.2794 -0.1016)
			(stroke
				(width 0.1)
				(type default)
			)
			(layer "B.Fab")
		)
		(fp_line
			(start 0.2794 -0.1016)
			(end 0.2794 0.9906)
			(stroke
				(width 0.1)
				(type default)
			)
			(layer "B.Fab")
		)
		(pad "1" smd rect
			(at 0 0 90)
			(size 0.508 0.508)
			(layers "B.Cu" "B.Mask" "B.Paste")
			(net "H_CPU1_CATERR_G_N")
		)
		(pad "2" smd rect
			(at 0 0.889 90)
			(size 0.508 0.508)
			(layers "B.Cu" "B.Mask" "B.Paste")
			(net "H_CPU_CATERR_G_N")
		)
		(zone
			(layer "B.Cu")
			(hatch none 0.5)
			(connect_pads
				(clearance 0)
			)
			(min_thickness 0.25)
			(keepout
				(tracks not_allowed)
				(vias allowed)
				(pads allowed)
				(copperpour not_allowed)
				(footprints allowed)
			)
			(placement
				(enabled no)
				(sheetname "")
			)
			(fill
				(thermal_gap 0.5)
				(thermal_bridge_width 0.5)
				(island_removal_mode 0)
			)
			(polygon
				(pts
					(xy 373.0625 -57.404) (xy 373.0625 -57.912) (xy 373.4435 -57.912) (xy 373.4435 -57.404)
				)
			)
		)
		(zone
			(layer "B.Cu")
			(hatch none 0.5)
			(connect_pads
				(clearance 0)
			)
			(min_thickness 0.25)
			(keepout
				(tracks allowed)
				(vias not_allowed)
				(pads allowed)
				(copperpour not_allowed)
				(footprints allowed)
			)
			(placement
				(enabled no)
				(sheetname "")
			)
			(fill
				(thermal_gap 0.5)
				(thermal_bridge_width 0.5)
				(island_removal_mode 0)
			)
			(polygon
				(pts
					(xy 373.4435 -57.404) (xy 373.4435 -57.912) (xy 373.0625 -57.912) (xy 373.0625 -57.404)
				)
			)
		)
	)
	(footprint ""
		(layer "B.Cu")
		(at 340.331806 -61.257434)
		(property "Reference" "C2U8"
			(at 0 0 0)
			(layer "B.SilkS")
			(hide yes)
			(effects
				(font
					(size 1.27 1.27)
				)
				(justify mirror)
			)
		)
		(property "Value" ""
			(at 0 0 0)
			(layer "B.Fab")
			(effects
				(font
					(size 1.27 1.27)
				)
				(justify mirror)
			)
		)
		(duplicate_pad_numbers_are_jumpers no)
		(fp_poly
			(pts
				(xy -0.3048 -0.1016) (xy -0.3048 0.9906) (xy 0.3048 0.9906) (xy 0.3048 -0.1016)
			)
			(stroke
				(width 0)
				(type default)
			)
			(fill no)
			(layer "B.CrtYd")
		)
		(fp_line
			(start -0.3048 -0.1016)
			(end 0.3048 -0.1016)
			(stroke
				(width 0.1)
				(type default)
			)
			(layer "B.Fab")
		)
		(fp_line
			(start -0.3048 0.9906)
			(end -0.3048 -0.1016)
			(stroke
				(width 0.1)
				(type default)
			)
			(layer "B.Fab")
		)
		(fp_line
			(start 0.3048 -0.1016)
			(end 0.3048 0.9906)
			(stroke
				(width 0.1)
				(type default)
			)
			(layer "B.Fab")
		)
		(fp_line
			(start 0.3048 0.9906)
			(end -0.3048 0.9906)
			(stroke
				(width 0.1)
				(type default)
			)
			(layer "B.Fab")
		)
		(pad "1" smd rect
			(at 0 0 180)
			(size 0.508 0.508)
			(layers "B.Cu" "B.Mask" "B.Paste")
			(net "P3E_CPU0_PE1_PCH_RXN<2>")
		)
		(pad "2" smd rect
			(at 0 0.889 180)
			(size 0.508 0.508)
			(layers "B.Cu" "B.Mask" "B.Paste")
			(net "P3E_CPU0_PE1_SS_RXN<2>")
		)
		(zone
			(layer "B.Cu")
			(hatch none 0.5)
			(connect_pads
				(clearance 0)
			)
			(min_thickness 0.25)
			(keepout
				(tracks allowed)
				(vias not_allowed)
				(pads allowed)
				(copperpour not_allowed)
				(footprints allowed)
			)
			(placement
				(enabled no)
				(sheetname "")
			)
			(fill
				(thermal_gap 0.5)
				(thermal_bridge_width 0.5)
				(island_removal_mode 0)
			)
			(polygon
				(pts
					(xy 340.585806 -61.003434) (xy 340.077806 -61.003434) (xy 340.077806 -60.622434) (xy 340.585806 -60.622434)
				)
			)
		)
		(zone
			(layer "B.Cu")
			(hatch none 0.5)
			(connect_pads
				(clearance 0)
			)
			(min_thickness 0.25)
			(keepout
				(tracks not_allowed)
				(vias allowed)
				(pads allowed)
				(copperpour not_allowed)
				(footprints allowed)
			)
			(placement
				(enabled no)
				(sheetname "")
			)
			(fill
				(thermal_gap 0.5)
				(thermal_bridge_width 0.5)
				(island_removal_mode 0)
			)
			(polygon
				(pts
					(xy 340.585806 -60.622434) (xy 340.077806 -60.622434) (xy 340.077806 -61.003434) (xy 340.585806 -61.003434)
				)
			)
		)
	)
)
